(kicad_pcb
	(version 20260206)
	(generator "pcbnew")
	(generator_version "10.0")
	(general
		(thickness 1.6)
		(legacy_teardrops no)
	)
	(paper "A4")
	(title_block
		(title "04192023_DAF0TMB3IC0_F0TG_MB_C_brd_V02_OCP.brd")
		(comment 1 "Grand Teton / footprint 2783 of 8354 (U26), pads 219-327 of 6102")
	)
	(layers
		(0 "F.Cu" signal "TOP")
		(4 "In1.Cu" signal "GND")
		(6 "In2.Cu" signal "IN1")
		(8 "In3.Cu" signal "GND1")
		(10 "In4.Cu" signal "IN2")
		(12 "In5.Cu" signal "GND2")
		(14 "In6.Cu" signal "IN3")
		(16 "In7.Cu" signal "GND3")
		(18 "In8.Cu" signal "VCC")
		(20 "In9.Cu" signal "VCC1")
		(22 "In10.Cu" signal "GND4")
		(24 "In11.Cu" signal "IN4")
		(26 "In12.Cu" signal "GND5")
		(28 "In13.Cu" signal "IN5")
		(30 "In14.Cu" signal "GND6")
		(32 "In15.Cu" signal "IN6")
		(34 "In16.Cu" signal "GND7")
		(2 "B.Cu" signal "BOTTOM")
		(9 "F.Adhes" user "F.Adhesive")
		(11 "B.Adhes" user "B.Adhesive")
		(13 "F.Paste" user "Package Geometry/Pastemask Top")
		(15 "B.Paste" user "Package Geometry/Pastemask Bottom")
		(5 "F.SilkS" user "Ref Des/Silkscreen Top")
		(7 "B.SilkS" user "Ref Des/Silkscreen Bottom")
		(1 "F.Mask" user "Board Geometry/Soldermask Top")
		(3 "B.Mask" user "Board Geometry/Soldermask Bottom")
		(17 "Dwgs.User" user "User.Drawings")
		(19 "Cmts.User" user "User.Comments")
		(21 "Eco1.User" user "User.Eco1")
		(23 "Eco2.User" user "User.Eco2")
		(25 "Edge.Cuts" user "Board Geometry/Outline")
		(27 "Margin" user)
		(31 "F.CrtYd" user "Package Geometry/Place Bound Top")
		(29 "B.CrtYd" user "Package Geometry/Place Bound Bottom")
		(35 "F.Fab" user "Ref Des/Assembly Top")
		(33 "B.Fab" user "Ref Des/Assembly Bottom")
	)
	(footprint ""
		(layer "F.Cu")
		(at 111.927894 -258.880356 180)
		(property "Reference" "U26"
			(at -45.05579 -61.794136 0)
			(unlocked yes)
			(layer "F.SilkS")
			(effects
				(font
					(size 0.7874 0.5842)
					(thickness 0.1524)
				)
			)
		)
		(property "Value" ""
			(at 0 0 180)
			(layer "F.Fab")
			(effects
				(font
					(size 1.27 1.27)
				)
			)
		)
		(duplicate_pad_numbers_are_jumpers no)
		(pad "AC13" smd circle
			(at -22.880066 -18.990056 180)
			(size 0.450088 0.450088)
			(layers "F.Cu" "F.Mask" "F.Paste")
			(net "GND")
		)
		(pad "AC14" smd circle
			(at -21.940012 -18.990056 180)
			(size 0.450088 0.450088)
			(layers "F.Cu" "F.Mask" "F.Paste")
			(net "M_H_CPU1_SA_DQ<23>")
		)
		(pad "AC15" smd circle
			(at -20.999958 -18.990056 180)
			(size 0.450088 0.450088)
			(layers "F.Cu" "F.Mask" "F.Paste")
			(net "GND")
		)
		(pad "AC16" smd circle
			(at -20.059904 -18.990056 180)
			(size 0.450088 0.450088)
			(layers "F.Cu" "F.Mask" "F.Paste")
			(net "M_J_CPU1_SA_DQ<24>")
		)
		(pad "AC17" smd circle
			(at -19.120104 -18.990056 180)
			(size 0.450088 0.450088)
			(layers "F.Cu" "F.Mask" "F.Paste")
			(net "M_J_CPU1_SA_DQ<23>")
		)
		(pad "AC18" smd circle
			(at -18.18005 -18.990056 180)
			(size 0.450088 0.450088)
			(layers "F.Cu" "F.Mask" "F.Paste")
			(net "PVDDCR_SOC_P1")
		)
		(pad "AC19" smd circle
			(at -17.239996 -18.990056 180)
			(size 0.450088 0.450088)
			(layers "F.Cu" "F.Mask" "F.Paste")
			(net "M_I_CPU1_SA_DQ<24>")
		)
		(pad "AC20" smd circle
			(at -16.299942 -18.990056 180)
			(size 0.450088 0.450088)
			(layers "F.Cu" "F.Mask" "F.Paste")
			(net "GND")
		)
		(pad "AC21" smd circle
			(at -15.359888 -18.990056 180)
			(size 0.450088 0.450088)
			(layers "F.Cu" "F.Mask" "F.Paste")
			(net "M_I_CPU1_SA_DQ<23>")
		)
		(pad "AC22" smd circle
			(at -14.420088 -18.990056 180)
			(size 0.450088 0.450088)
			(layers "F.Cu" "F.Mask" "F.Paste")
			(net "GND")
		)
		(pad "AC23" smd circle
			(at -13.480034 -18.990056 180)
			(size 0.450088 0.450088)
			(layers "F.Cu" "F.Mask" "F.Paste")
			(net "GMI_CPU0_G0_CPU1_G2_TX_DN<14>")
		)
		(pad "AC24" smd circle
			(at -12.53998 -18.990056 180)
			(size 0.450088 0.450088)
			(layers "F.Cu" "F.Mask" "F.Paste")
			(net "GMI_CPU0_G0_CPU1_G2_TX_DP<14>")
		)
		(pad "AC25" smd circle
			(at -11.599926 -18.990056 180)
			(size 0.450088 0.450088)
			(layers "F.Cu" "F.Mask" "F.Paste")
			(net "GND")
		)
		(pad "AC26" smd circle
			(at -10.659872 -18.990056 180)
			(size 0.450088 0.450088)
			(layers "F.Cu" "F.Mask" "F.Paste")
			(net "GMI_CPU0_G0_CPU1_G2_TX_DN<11>")
		)
		(pad "AC27" smd circle
			(at -9.720072 -18.990056 180)
			(size 0.450088 0.450088)
			(layers "F.Cu" "F.Mask" "F.Paste")
			(net "GMI_CPU0_G0_CPU1_G2_TX_DP<11>")
		)
		(pad "AC28" smd circle
			(at -8.780018 -18.990056 180)
			(size 0.450088 0.450088)
			(layers "F.Cu" "F.Mask" "F.Paste")
			(net "GND")
		)
		(pad "AC29" smd circle
			(at -7.839964 -18.990056 180)
			(size 0.450088 0.450088)
			(layers "F.Cu" "F.Mask" "F.Paste")
			(net "GMI_CPU0_G0_CPU1_G2_TX_DN<8>")
		)
		(pad "AC30" smd circle
			(at -6.89991 -18.990056 180)
			(size 0.450088 0.450088)
			(layers "F.Cu" "F.Mask" "F.Paste")
			(net "GMI_CPU0_G0_CPU1_G2_TX_DP<8>")
		)
		(pad "AC31" smd circle
			(at -5.96011 -18.990056 180)
			(size 0.450088 0.450088)
			(layers "F.Cu" "F.Mask" "F.Paste")
			(net "GND")
		)
		(pad "AC32" smd circle
			(at -5.020056 -18.990056 180)
			(size 0.450088 0.450088)
			(layers "F.Cu" "F.Mask" "F.Paste")
			(net "GMI_CPU0_G0_CPU1_G2_TX_DN<5>")
		)
		(pad "AC33" smd circle
			(at -4.080002 -18.990056 180)
			(size 0.450088 0.450088)
			(layers "F.Cu" "F.Mask" "F.Paste")
			(net "GMI_CPU0_G0_CPU1_G2_TX_DP<5>")
		)
		(pad "AC34" smd circle
			(at -3.139948 -18.990056 180)
			(size 0.450088 0.450088)
			(layers "F.Cu" "F.Mask" "F.Paste")
			(net "GND")
		)
		(pad "AC35" smd circle
			(at -2.199894 -18.990056 180)
			(size 0.450088 0.450088)
			(layers "F.Cu" "F.Mask" "F.Paste")
			(net "PVDDCR_CPU0_P1")
		)
		(pad "AC36" smd circle
			(at -1.260094 -18.990056 180)
			(size 0.450088 0.450088)
			(layers "F.Cu" "F.Mask" "F.Paste")
			(net "PVDDCR_CPU0_P1")
		)
		(pad "AC40" smd circle
			(at 1.560068 -18.990056 180)
			(size 0.450088 0.450088)
			(layers "F.Cu" "F.Mask" "F.Paste")
			(net "PVDDCR_CPU0_P1")
		)
		(pad "AC41" smd circle
			(at 2.500122 -18.990056 180)
			(size 0.450088 0.450088)
			(layers "F.Cu" "F.Mask" "F.Paste")
			(net "PVDDCR_CPU0_P1")
		)
		(pad "AC42" smd circle
			(at 3.439922 -18.990056 180)
			(size 0.450088 0.450088)
			(layers "F.Cu" "F.Mask" "F.Paste")
			(net "GND")
		)
		(pad "AC43" smd circle
			(at 4.379976 -18.990056 180)
			(size 0.450088 0.450088)
			(layers "F.Cu" "F.Mask" "F.Paste")
			(net "GMI_CPU1_G0_CPU0_G2_TX_DP<10>")
		)
		(pad "AC44" smd circle
			(at 5.32003 -18.990056 180)
			(size 0.450088 0.450088)
			(layers "F.Cu" "F.Mask" "F.Paste")
			(net "GMI_CPU1_G0_CPU0_G2_TX_DN<10>")
		)
		(pad "AC45" smd circle
			(at 6.260084 -18.990056 180)
			(size 0.450088 0.450088)
			(layers "F.Cu" "F.Mask" "F.Paste")
			(net "GND")
		)
		(pad "AC46" smd circle
			(at 7.199884 -18.990056 180)
			(size 0.450088 0.450088)
			(layers "F.Cu" "F.Mask" "F.Paste")
			(net "GMI_CPU1_G0_CPU0_G2_TX_DP<7>")
		)
		(pad "AC47" smd circle
			(at 8.139938 -18.990056 180)
			(size 0.450088 0.450088)
			(layers "F.Cu" "F.Mask" "F.Paste")
			(net "GMI_CPU1_G0_CPU0_G2_TX_DN<7>")
		)
		(pad "AC48" smd circle
			(at 9.079992 -18.990056 180)
			(size 0.450088 0.450088)
			(layers "F.Cu" "F.Mask" "F.Paste")
			(net "GND")
		)
		(pad "AC49" smd circle
			(at 10.020046 -18.990056 180)
			(size 0.450088 0.450088)
			(layers "F.Cu" "F.Mask" "F.Paste")
			(net "GMI_CPU1_G0_CPU0_G2_TX_DP<4>")
		)
		(pad "AC50" smd circle
			(at 10.9601 -18.990056 180)
			(size 0.450088 0.450088)
			(layers "F.Cu" "F.Mask" "F.Paste")
			(net "GMI_CPU1_G0_CPU0_G2_TX_DN<4>")
		)
		(pad "AC51" smd circle
			(at 11.8999 -18.990056 180)
			(size 0.450088 0.450088)
			(layers "F.Cu" "F.Mask" "F.Paste")
			(net "GND")
		)
		(pad "AC52" smd circle
			(at 12.839954 -18.990056 180)
			(size 0.450088 0.450088)
			(layers "F.Cu" "F.Mask" "F.Paste")
			(net "GMI_CPU1_G0_CPU0_G2_TX_DP<1>")
		)
		(pad "AC53" smd circle
			(at 13.780008 -18.990056 180)
			(size 0.450088 0.450088)
			(layers "F.Cu" "F.Mask" "F.Paste")
			(net "GMI_CPU1_G0_CPU0_G2_TX_DN<1>")
		)
		(pad "AC54" smd circle
			(at 14.720062 -18.990056 180)
			(size 0.450088 0.450088)
			(layers "F.Cu" "F.Mask" "F.Paste")
			(net "GND")
		)
		(pad "AC55" smd circle
			(at 15.660116 -18.990056 180)
			(size 0.450088 0.450088)
			(layers "F.Cu" "F.Mask" "F.Paste")
			(net "M_C_CPU1_SA_DQ<23>")
		)
		(pad "AC56" smd circle
			(at 16.599916 -18.990056 180)
			(size 0.450088 0.450088)
			(layers "F.Cu" "F.Mask" "F.Paste")
			(net "GND")
		)
		(pad "AC57" smd circle
			(at 17.53997 -18.990056 180)
			(size 0.450088 0.450088)
			(layers "F.Cu" "F.Mask" "F.Paste")
			(net "M_C_CPU1_SA_DQ<24>")
		)
		(pad "AC58" smd circle
			(at 18.480024 -18.990056 180)
			(size 0.450088 0.450088)
			(layers "F.Cu" "F.Mask" "F.Paste")
			(net "PVDDIO_P1")
		)
		(pad "AC59" smd circle
			(at 19.420078 -18.990056 180)
			(size 0.450088 0.450088)
			(layers "F.Cu" "F.Mask" "F.Paste")
			(net "M_D_CPU1_SA_DQ<23>")
		)
		(pad "AC60" smd circle
			(at 20.359878 -18.990056 180)
			(size 0.450088 0.450088)
			(layers "F.Cu" "F.Mask" "F.Paste")
			(net "M_D_CPU1_SA_DQ<24>")
		)
		(pad "AC61" smd circle
			(at 21.299932 -18.990056 180)
			(size 0.450088 0.450088)
			(layers "F.Cu" "F.Mask" "F.Paste")
			(net "GND")
		)
		(pad "AC62" smd circle
			(at 22.239986 -18.990056 180)
			(size 0.450088 0.450088)
			(layers "F.Cu" "F.Mask" "F.Paste")
			(net "M_B_CPU1_SA_DQ<23>")
		)
		(pad "AC63" smd circle
			(at 23.18004 -18.990056 180)
			(size 0.450088 0.450088)
			(layers "F.Cu" "F.Mask" "F.Paste")
			(net "GND")
		)
		(pad "AC64" smd circle
			(at 24.120094 -18.990056 180)
			(size 0.450088 0.450088)
			(layers "F.Cu" "F.Mask" "F.Paste")
			(net "M_B_CPU1_SA_DQ<24>")
		)
		(pad "AC65" smd circle
			(at 25.059894 -18.990056 180)
			(size 0.450088 0.450088)
			(layers "F.Cu" "F.Mask" "F.Paste")
			(net "PVDDIO_P1")
		)
		(pad "AC66" smd circle
			(at 25.999948 -18.990056 180)
			(size 0.450088 0.450088)
			(layers "F.Cu" "F.Mask" "F.Paste")
			(net "M_F_CPU1_SA_DQ<23>")
		)
		(pad "AC67" smd circle
			(at 26.940002 -18.990056 180)
			(size 0.450088 0.450088)
			(layers "F.Cu" "F.Mask" "F.Paste")
			(net "M_F_CPU1_SA_DQ<24>")
		)
		(pad "AC68" smd circle
			(at 27.880056 -18.990056 180)
			(size 0.450088 0.450088)
			(layers "F.Cu" "F.Mask" "F.Paste")
			(net "GND")
		)
		(pad "AC69" smd circle
			(at 28.82011 -18.990056 180)
			(size 0.450088 0.450088)
			(layers "F.Cu" "F.Mask" "F.Paste")
			(net "M_E_CPU1_SA_DQ<23>")
		)
		(pad "AC70" smd circle
			(at 29.75991 -18.990056 180)
			(size 0.450088 0.450088)
			(layers "F.Cu" "F.Mask" "F.Paste")
			(net "GND")
		)
		(pad "AC71" smd circle
			(at 30.699964 -18.990056 180)
			(size 0.450088 0.450088)
			(layers "F.Cu" "F.Mask" "F.Paste")
			(net "M_E_CPU1_SA_DQ<24>")
		)
		(pad "AC72" smd circle
			(at 31.640018 -18.990056 180)
			(size 0.450088 0.450088)
			(layers "F.Cu" "F.Mask" "F.Paste")
			(net "PVDDIO_P1")
		)
		(pad "AC73" smd circle
			(at 32.580072 -18.990056 180)
			(size 0.450088 0.450088)
			(layers "F.Cu" "F.Mask" "F.Paste")
			(net "M_A_CPU1_SA_DQ<23>")
		)
		(pad "AC74" smd circle
			(at 33.519872 -18.990056 180)
			(size 0.450088 0.450088)
			(layers "F.Cu" "F.Mask" "F.Paste")
			(net "M_A_CPU1_SA_DQ<24>")
		)
		(pad "AC75" smd circle
			(at 34.459926 -18.990056 180)
			(size 0.450088 0.450088)
			(layers "F.Cu" "F.Mask" "F.Paste")
			(net "GND")
		)
		(pad "AD2" smd circle
			(at -33.690052 -18.18005 180)
			(size 0.450088 0.450088)
			(layers "F.Cu" "F.Mask" "F.Paste")
			(net "M_G_CPU1_SA_DQ<26>")
		)
		(pad "AD3" smd circle
			(at -32.749998 -18.18005 180)
			(size 0.450088 0.450088)
			(layers "F.Cu" "F.Mask" "F.Paste")
			(net "GND")
		)
		(pad "AD4" smd circle
			(at -31.809944 -18.18005 180)
			(size 0.450088 0.450088)
			(layers "F.Cu" "F.Mask" "F.Paste")
			(net "M_G_CPU1_SA_DQ<25>")
		)
		(pad "AD5" smd circle
			(at -30.86989 -18.18005 180)
			(size 0.450088 0.450088)
			(layers "F.Cu" "F.Mask" "F.Paste")
			(net "GND")
		)
		(pad "AD6" smd circle
			(at -29.93009 -18.18005 180)
			(size 0.450088 0.450088)
			(layers "F.Cu" "F.Mask" "F.Paste")
			(net "M_K_CPU1_SA_DQ<26>")
		)
		(pad "AD7" smd circle
			(at -28.990036 -18.18005 180)
			(size 0.450088 0.450088)
			(layers "F.Cu" "F.Mask" "F.Paste")
			(net "M_K_CPU1_SA_DQ<25>")
		)
		(pad "AD8" smd circle
			(at -28.049982 -18.18005 180)
			(size 0.450088 0.450088)
			(layers "F.Cu" "F.Mask" "F.Paste")
			(net "GND")
		)
		(pad "AD9" smd circle
			(at -27.109928 -18.18005 180)
			(size 0.450088 0.450088)
			(layers "F.Cu" "F.Mask" "F.Paste")
			(net "M_L_CPU1_SA_DQ<26>")
		)
		(pad "AD10" smd circle
			(at -26.170128 -18.18005 180)
			(size 0.450088 0.450088)
			(layers "F.Cu" "F.Mask" "F.Paste")
			(net "GND")
		)
		(pad "AD11" smd circle
			(at -25.230074 -18.18005 180)
			(size 0.450088 0.450088)
			(layers "F.Cu" "F.Mask" "F.Paste")
			(net "M_L_CPU1_SA_DQ<25>")
		)
		(pad "AD12" smd circle
			(at -24.29002 -18.18005 180)
			(size 0.450088 0.450088)
			(layers "F.Cu" "F.Mask" "F.Paste")
			(net "GND")
		)
		(pad "AD13" smd circle
			(at -23.349966 -18.18005 180)
			(size 0.450088 0.450088)
			(layers "F.Cu" "F.Mask" "F.Paste")
			(net "M_H_CPU1_SA_DQ<26>")
		)
		(pad "AD14" smd circle
			(at -22.409912 -18.18005 180)
			(size 0.450088 0.450088)
			(layers "F.Cu" "F.Mask" "F.Paste")
			(net "M_H_CPU1_SA_DQ<25>")
		)
		(pad "AD15" smd circle
			(at -21.470112 -18.18005 180)
			(size 0.450088 0.450088)
			(layers "F.Cu" "F.Mask" "F.Paste")
			(net "GND")
		)
		(pad "AD16" smd circle
			(at -20.530058 -18.18005 180)
			(size 0.450088 0.450088)
			(layers "F.Cu" "F.Mask" "F.Paste")
			(net "M_J_CPU1_SA_DQ<26>")
		)
		(pad "AD17" smd circle
			(at -19.590004 -18.18005 180)
			(size 0.450088 0.450088)
			(layers "F.Cu" "F.Mask" "F.Paste")
			(net "GND")
		)
		(pad "AD18" smd circle
			(at -18.64995 -18.18005 180)
			(size 0.450088 0.450088)
			(layers "F.Cu" "F.Mask" "F.Paste")
			(net "M_J_CPU1_SA_DQ<25>")
		)
		(pad "AD19" smd circle
			(at -17.709896 -18.18005 180)
			(size 0.450088 0.450088)
			(layers "F.Cu" "F.Mask" "F.Paste")
			(net "GND")
		)
		(pad "AD20" smd circle
			(at -16.770096 -18.18005 180)
			(size 0.450088 0.450088)
			(layers "F.Cu" "F.Mask" "F.Paste")
			(net "M_I_CPU1_SA_DQ<26>")
		)
		(pad "AD21" smd circle
			(at -15.830042 -18.18005 180)
			(size 0.450088 0.450088)
			(layers "F.Cu" "F.Mask" "F.Paste")
			(net "M_I_CPU1_SA_DQ<25>")
		)
		(pad "AD22" smd circle
			(at -14.889988 -18.18005 180)
			(size 0.450088 0.450088)
			(layers "F.Cu" "F.Mask" "F.Paste")
			(net "PVDDCR_SOC_P1")
		)
		(pad "AD23" smd circle
			(at -13.949934 -18.18005 180)
			(size 0.450088 0.450088)
			(layers "F.Cu" "F.Mask" "F.Paste")
			(net "GND")
		)
		(pad "AD24" smd circle
			(at -13.00988 -18.18005 180)
			(size 0.450088 0.450088)
			(layers "F.Cu" "F.Mask" "F.Paste")
			(net "GND")
		)
		(pad "AD25" smd circle
			(at -12.07008 -18.18005 180)
			(size 0.450088 0.450088)
			(layers "F.Cu" "F.Mask" "F.Paste")
			(net "GND")
		)
		(pad "AD26" smd circle
			(at -11.130026 -18.18005 180)
			(size 0.450088 0.450088)
			(layers "F.Cu" "F.Mask" "F.Paste")
			(net "GND")
		)
		(pad "AD27" smd circle
			(at -10.189972 -18.18005 180)
			(size 0.450088 0.450088)
			(layers "F.Cu" "F.Mask" "F.Paste")
			(net "GND")
		)
		(pad "AD28" smd circle
			(at -9.249918 -18.18005 180)
			(size 0.450088 0.450088)
			(layers "F.Cu" "F.Mask" "F.Paste")
			(net "GND")
		)
		(pad "AD29" smd circle
			(at -8.310118 -18.18005 180)
			(size 0.450088 0.450088)
			(layers "F.Cu" "F.Mask" "F.Paste")
			(net "GND")
		)
		(pad "AD30" smd circle
			(at -7.370064 -18.18005 180)
			(size 0.450088 0.450088)
			(layers "F.Cu" "F.Mask" "F.Paste")
			(net "GND")
		)
		(pad "AD31" smd circle
			(at -6.43001 -18.18005 180)
			(size 0.450088 0.450088)
			(layers "F.Cu" "F.Mask" "F.Paste")
			(net "GND")
		)
		(pad "AD32" smd circle
			(at -5.489956 -18.18005 180)
			(size 0.450088 0.450088)
			(layers "F.Cu" "F.Mask" "F.Paste")
			(net "GND")
		)
		(pad "AD33" smd circle
			(at -4.549902 -18.18005 180)
			(size 0.450088 0.450088)
			(layers "F.Cu" "F.Mask" "F.Paste")
			(net "GND")
		)
		(pad "AD34" smd circle
			(at -3.610102 -18.18005 180)
			(size 0.450088 0.450088)
			(layers "F.Cu" "F.Mask" "F.Paste")
			(net "GND")
		)
		(pad "AD35" smd circle
			(at -2.670048 -18.18005 180)
			(size 0.450088 0.450088)
			(layers "F.Cu" "F.Mask" "F.Paste")
			(net "GMI_CPU0_G0_CPU1_G2_TX_DN<1>")
		)
		(pad "AD36" smd circle
			(at -1.729994 -18.18005 180)
			(size 0.450088 0.450088)
			(layers "F.Cu" "F.Mask" "F.Paste")
			(net "GMI_CPU0_G0_CPU1_G2_TX_DP<1>")
		)
		(pad "AD37" smd circle
			(at -0.78994 -18.18005 180)
			(size 0.450088 0.450088)
			(layers "F.Cu" "F.Mask" "F.Paste")
			(net "GND")
		)
		(pad "AD39" smd circle
			(at 1.089914 -18.18005 180)
			(size 0.450088 0.450088)
			(layers "F.Cu" "F.Mask" "F.Paste")
			(net "GND")
		)
		(pad "AD40" smd circle
			(at 2.029968 -18.18005 180)
			(size 0.450088 0.450088)
			(layers "F.Cu" "F.Mask" "F.Paste")
			(net "GMI_CPU1_G0_CPU0_G2_TX_DP<14>")
		)
		(pad "AD41" smd circle
			(at 2.970022 -18.18005 180)
			(size 0.450088 0.450088)
			(layers "F.Cu" "F.Mask" "F.Paste")
			(net "GMI_CPU1_G0_CPU0_G2_TX_DN<14>")
		)
		(pad "AD42" smd circle
			(at 3.910076 -18.18005 180)
			(size 0.450088 0.450088)
			(layers "F.Cu" "F.Mask" "F.Paste")
			(net "GND")
		)
		(pad "AD43" smd circle
			(at 4.849876 -18.18005 180)
			(size 0.450088 0.450088)
			(layers "F.Cu" "F.Mask" "F.Paste")
			(net "GND")
		)
		(pad "AD44" smd circle
			(at 5.78993 -18.18005 180)
			(size 0.450088 0.450088)
			(layers "F.Cu" "F.Mask" "F.Paste")
			(net "GND")
		)
		(pad "AD45" smd circle
			(at 6.729984 -18.18005 180)
			(size 0.450088 0.450088)
			(layers "F.Cu" "F.Mask" "F.Paste")
			(net "GND")
		)
		(pad "AD46" smd circle
			(at 7.670038 -18.18005 180)
			(size 0.450088 0.450088)
			(layers "F.Cu" "F.Mask" "F.Paste")
			(net "GND")
		)
		(pad "AD47" smd circle
			(at 8.610092 -18.18005 180)
			(size 0.450088 0.450088)
			(layers "F.Cu" "F.Mask" "F.Paste")
			(net "GND")
		)
		(pad "AD48" smd circle
			(at 9.549892 -18.18005 180)
			(size 0.450088 0.450088)
			(layers "F.Cu" "F.Mask" "F.Paste")
			(net "GND")
		)
		(pad "AD49" smd circle
			(at 10.489946 -18.18005 180)
			(size 0.450088 0.450088)
			(layers "F.Cu" "F.Mask" "F.Paste")
			(net "GND")
		)
		(pad "AD50" smd circle
			(at 11.43 -18.18005 180)
			(size 0.450088 0.450088)
			(layers "F.Cu" "F.Mask" "F.Paste")
			(net "GND")
		)
		(pad "AD51" smd circle
			(at 12.370054 -18.18005 180)
			(size 0.450088 0.450088)
			(layers "F.Cu" "F.Mask" "F.Paste")
			(net "GND")
		)
	)
)
